FILE_TYPE = MACRO_DRAWING;
SET COLOR_WIRE YELLOW;
SET COLOR_PROP ORANGE;
SET COLOR_DOT WHITE;
SET COLOR_ARC YELLOW;
SET COLOR_BODY GREEN;
SET COLOR_NOTE PURPLE;
SET PROP_DISPLAY VALUE;
SET PAGE_NUMBER P39;
SET PATH_NUMBER P3;
FORCEADD LCMXO3LF2100C5BG256C..6
(-4800 4375);
FORCEPROP 1 LAST PART_NUMBER AJ021000T03
J 0
(-5393 5147);
DISPLAY 0.723404 (-5393 5147);
PAINT GREEN (-5393 5147);
FORCEPROP 2 LAST VALUE LCMXO3LF-2100C-5BG256C
J 0
(-5375 5300);
DISPLAY 0.680851 (-5375 5300);
FORCEPROP 1 LAST MATERIAL IC
J 0
(-5393 5056);
DISPLAY 0.723404 (-5393 5056);
PAINT GREEN (-5393 5056);
FORCEPROP 2 LAST PART_TYPE SMLF
J 0
(-5375 5350);
DISPLAY 0.680851 (-5375 5350);
FORCEPROP 1 LAST CDS_LMAN_SYM_OUTLINE -600,675,600,-675
J 0
(-4800 4375);
DISPLAY 0.468085 (-4800 4375);
PAINT GREEN (-4800 4375);
DISPLAY INVISIBLE (-4800 4375);
FORCEPROP 1 LAST NEEDS_NO_SIZE TRUE
J 0
(-4800 4375);
DISPLAY 0.723404 (-4800 4375);
PAINT GREEN (-4800 4375);
DISPLAY INVISIBLE (-4800 4375);
FORCEPROP 1 LAST PATH I1
J 0
(-4800 4375);
DISPLAY 0.723404 (-4800 4375);
PAINT GREEN (-4800 4375);
DISPLAY INVISIBLE (-4800 4375);
FORCEPROP 2 LAST CDS_LIB pure_quanta
J 0
(-4800 4375);
DISPLAY INVISIBLE (-4800 4375);
FORCEPROP 1 LAST LOCATION U25
J 0
(-5393 5246);
DISPLAY 0.723404 (-5393 5246);
PAINT GREEN (-5393 5246);
FORCEPROP 0 LASTPIN (-5550 4750) $PN D3
J 2
(-5560 4760);
DISPLAY 0.680851 (-5560 4760);
PAINT MONO (-5560 4760);
FORCEPROP 0 LASTPIN (-5550 4700) $PN D1
J 2
(-5560 4710);
DISPLAY 0.680851 (-5560 4710);
PAINT MONO (-5560 4710);
FORCEPROP 0 LASTPIN (-5550 4900) $PN B1
J 2
(-5560 4910);
DISPLAY 0.680851 (-5560 4910);
PAINT MONO (-5560 4910);
FORCEPROP 0 LASTPIN (-5550 4850) $PN C2
J 2
(-5560 4860);
DISPLAY 0.680851 (-5560 4860);
PAINT MONO (-5560 4860);
FORCEPROP 0 LASTPIN (-5550 4600) $PN E2
J 2
(-5560 4610);
DISPLAY 0.680851 (-5560 4610);
PAINT MONO (-5560 4610);
FORCEPROP 0 LASTPIN (-5550 4550) $PN E3
J 2
(-5560 4560);
DISPLAY 0.680851 (-5560 4560);
PAINT MONO (-5560 4560);
FORCEPROP 0 LASTPIN (-5550 4450) $PN C1
J 2
(-5560 4460);
DISPLAY 0.680851 (-5560 4460);
PAINT MONO (-5560 4460);
FORCEPROP 0 LASTPIN (-5550 4400) $PN D2
J 2
(-5560 4410);
DISPLAY 0.680851 (-5560 4410);
PAINT MONO (-5560 4410);
FORCEPROP 0 LASTPIN (-5550 4300) $PN E1
J 2
(-5560 4310);
DISPLAY 0.680851 (-5560 4310);
PAINT MONO (-5560 4310);
FORCEPROP 0 LASTPIN (-5550 4250) $PN F2
J 2
(-5560 4260);
DISPLAY 0.680851 (-5560 4260);
PAINT MONO (-5560 4260);
FORCEPROP 0 LASTPIN (-5550 4150) $PN F4
J 2
(-5560 4160);
DISPLAY 0.680851 (-5560 4160);
PAINT MONO (-5560 4160);
FORCEPROP 0 LASTPIN (-5550 4100) $PN G6
J 2
(-5560 4110);
DISPLAY 0.680851 (-5560 4110);
PAINT MONO (-5560 4110);
FORCEPROP 0 LASTPIN (-4050 4750) $PN F3
J 0
(-4040 4760);
DISPLAY 0.680851 (-4040 4760);
PAINT MONO (-4040 4760);
FORCEPROP 0 LASTPIN (-4050 4700) $PN F1
J 0
(-4040 4710);
DISPLAY 0.680851 (-4040 4710);
PAINT MONO (-4040 4710);
FORCEPROP 0 LASTPIN (-4050 4900) $PN G5
J 0
(-4040 4910);
DISPLAY 0.680851 (-4040 4910);
PAINT MONO (-4040 4910);
FORCEPROP 0 LASTPIN (-4050 4850) $PN G4
J 0
(-4040 4860);
DISPLAY 0.680851 (-4040 4860);
PAINT MONO (-4040 4860);
FORCEPROP 0 LASTPIN (-4050 4600) $PN G2
J 0
(-4040 4610);
DISPLAY 0.680851 (-4040 4610);
PAINT MONO (-4040 4610);
FORCEPROP 0 LASTPIN (-4050 4550) $PN G3
J 0
(-4040 4560);
DISPLAY 0.680851 (-4040 4560);
PAINT MONO (-4040 4560);
FORCEPROP 0 LASTPIN (-4050 4450) $PN F5
J 0
(-4040 4460);
DISPLAY 0.680851 (-4040 4460);
PAINT MONO (-4040 4460);
FORCEPROP 0 LASTPIN (-4050 4400) $PN H6
J 0
(-4040 4410);
DISPLAY 0.680851 (-4040 4410);
PAINT MONO (-4040 4410);
FORCEPROP 0 LASTPIN (-4050 3900) $PN E4
J 0
(-4040 3910);
DISPLAY 0.680851 (-4040 3910);
PAINT MONO (-4040 3910);
FORCEPROP 0 LAST $SEC 6
J 0
(-5375 5400);
DISPLAY 0.680851 (-5375 5400);
PAINT MONO (-5375 5400);
DISPLAY INVISIBLE (-5375 5400);
FORCEPROP 0 LAST CDS_SEC 6
J 0
(-5375 5400);
DISPLAY 0.680851 (-5375 5400);
DISPLAY INVISIBLE (-5375 5400);
FORCEADD UNIVERSAL_POWER..1
(-3675 4000);
FORCEPROP 3 LASTPIN (-3675 3950) SIG_NAME VCCIO5\g
J 0
(-3665 3960);
DISPLAY 0.659574 (-3665 3960);
PAINT MONO (-3665 3960);
DISPLAY INVISIBLE (-3665 3960);
FORCEPROP 1 LAST HDL_POWER VCCIO5
J 1
(-3675 4050);
DISPLAY 0.702128 (-3675 4050);
PAINT GREEN (-3675 4050);
FORCEPROP 2 LAST CDS_LIB logical_power
J 0
(-3675 4000);
DISPLAY INVISIBLE (-3675 4000);
FORCEPROP 1 LAST PATH I3
J 0
(-3625 4025);
DISPLAY 0.872340 (-3625 4025);
PAINT AQUA (-3625 4025);
DISPLAY INVISIBLE (-3625 4025);
FORCEADD QUANTA_TITLE_BLOCK_C..1
(0 0);
FORCEPROP 0 LAST CDS_CON_LAST_MODIFIED Fri Aug 25 17:25:45 2023
J 0
(-1885 15);
DISPLAY INVISIBLE (-1885 15);
FORCEPROP 2 LAST Q_DEPT 
J 1
(-3763 49);
DISPLAY 1.957447 (-3763 49);
PAINT GREEN (-3763 49);
FORCEPROP 1 LAST CUSTOM_TXT_CDS <CON_LAST_MODIFIED>
J 0
(-1885 15);
DISPLAY 0.978723 (-1885 15);
FORCEPROP 2 LAST CUSTOM_TXT_CDS <XR_PAGE_TITLE>
J 0
(-7890 5250);
DISPLAY 0.638298 (-7890 5250);
PAINT PINK (-7890 5250);
DISPLAY INVISIBLE (-7890 5250);
FORCEPROP 1 LAST CUSTOM_TXT_CDS <NAME_2>
J 0
(-3175 50);
FORCEPROP 1 LAST CUSTOM_TXT_CDS <NAME_1>
J 0
(-3175 175);
FORCEPROP 1 LAST CUSTOM_TXT_CDS <Q_NUMBER>
J 0
(-1403 103);
DISPLAY 1.212766 (-1403 103);
FORCEPROP 1 LAST CUSTOM_TXT_CDS <Q_PROJ>
J 0
(-2382 102);
DISPLAY 1.212766 (-2382 102);
FORCEPROP 1 LAST CUSTOM_TXT_CDS <Q_REV>
J 0
(-184 103);
DISPLAY 1.212766 (-184 103);
FORCEPROP 1 LAST CUSTOM_TXT_CDS <CON_PAGE_NUM> OF <CON_TOTAL_PAGES>
J 0
(-446 18);
DISPLAY 0.978723 (-446 18);
FORCEPROP 1 LAST Q_TITLE FPGA 6/8
J 0
(-9366 26);
DISPLAY 2.446809 (-9366 26);
PAINT GREEN (-9366 26);
FORCEPROP 2 LAST CDS_LIB pure_quanta
J 0
(0 0);
DISPLAY INVISIBLE (0 0);
FORCEPROP 1 LAST COMMENT_BODY TRUE
J 0
(12 -13);
DISPLAY 0.978723 (12 -13);
PAINT GREEN (12 -13);
DISPLAY INVISIBLE (12 -13);
FORCEPROP 1 LAST CDS_LMAN_SYM_OUTLINE -9475,6775,100,-125
J 0
(0 0);
DISPLAY 0.468085 (0 0);
PAINT GREEN (0 0);
DISPLAY INVISIBLE (0 0);
FORCEPROP 2 LAST PAGE_BORDER TRUE
J 0
(-7890 5250);
DISPLAY 0.638298 (-7890 5250);
PAINT PINK (-7890 5250);
DISPLAY INVISIBLE (-7890 5250);
FORCEPROP 2 LAST CDS_XR_PAGE_TITLE CR-39 : @SCM_LIB.SCM(SCH_1):PAGE39
J 0
(-7890 5250);
DISPLAY 0.638298 (-7890 5250);
PAINT PINK (-7890 5250);
DISPLAY INVISIBLE (-7890 5250);
WIRE 16 -1 (-3675 3950)(-3675 3900);
WIRE 16 -1 (-4050 3900)(-3675 3900);
QUIT
